(kicad_pcb
	(version 20260206)
	(generator "pcbnew")
	(generator_version "10.0")
	(general
		(thickness 1.6)
		(legacy_teardrops no)
	)
	(paper "A4")
	(title_block
		(title "peb — Lightning_PEB_BRD.brd")
		(comment 1 "Lightning (Wiwynn / Facebook NVMe JBOF) / footprints 701-708 of 2563")
	)
	(layers
		(0 "F.Cu" signal "TOP")
		(4 "In1.Cu" signal "L2GND")
		(6 "In2.Cu" signal "L3")
		(8 "In3.Cu" signal "L4VCC")
		(10 "In4.Cu" signal "L5VCC")
		(12 "In5.Cu" signal "L6")
		(14 "In6.Cu" signal "L7GND")
		(2 "B.Cu" signal "BOTTOM")
		(9 "F.Adhes" user "F.Adhesive")
		(11 "B.Adhes" user "B.Adhesive")
		(13 "F.Paste" user "Package Geometry/Pastemask Top")
		(15 "B.Paste" user "Package Geometry/Pastemask Bottom")
		(5 "F.SilkS" user "Ref Des/Silkscreen Top")
		(7 "B.SilkS" user "Ref Des/Silkscreen Bottom")
		(1 "F.Mask" user "Board Geometry/Soldermask Top")
		(3 "B.Mask" user "Board Geometry/Soldermask Bottom")
		(17 "Dwgs.User" user "User.Drawings")
		(19 "Cmts.User" user "User.Comments")
		(21 "Eco1.User" user "User.Eco1")
		(23 "Eco2.User" user "User.Eco2")
		(25 "Edge.Cuts" user "Board Geometry/Outline")
		(27 "Margin" user)
		(31 "F.CrtYd" user "Package Geometry/Place Bound Top")
		(29 "B.CrtYd" user "Package Geometry/Place Bound Bottom")
		(35 "F.Fab" user "Ref Des/Assembly Top")
		(33 "B.Fab" user "Ref Des/Assembly Bottom")
	)
	(footprint ""
		(layer "F.Cu")
		(at 42.4688 -183.2356)
		(property "Reference" "R865"
			(at 0 0 0)
			(layer "F.SilkS")
			(hide yes)
			(effects
				(font
					(size 1.27 1.27)
				)
			)
		)
		(property "Value" "0R2J-2-GP"
			(at 0.064008 -3.993896 0)
			(unlocked yes)
			(layer "F.Fab")
			(hide yes)
			(effects
				(font
					(size 1.016 1.016)
					(thickness 0.1524)
				)
			)
		)
		(property "Device Type" "R402H16"
			(at 0.064008 -5.517896 0)
			(unlocked yes)
			(layer "F.Fab")
			(hide yes)
			(effects
				(font
					(size 1.016 1.016)
					(thickness 0.1524)
				)
			)
		)
		(duplicate_pad_numbers_are_jumpers no)
		(fp_line
			(start -0.508 -0.9398)
			(end -0.508 0.9398)
			(stroke
				(width 0.1524)
				(type default)
			)
			(layer "F.SilkS")
		)
		(fp_line
			(start 0.508 -0.9398)
			(end -0.508 -0.9398)
			(stroke
				(width 0.1524)
				(type default)
			)
			(layer "F.SilkS")
		)
		(fp_rect
			(start -0.508 0.9398)
			(end 0.508 -0.9398)
			(stroke
				(width 0)
				(type default)
			)
			(fill no)
			(layer "F.CrtYd")
		)
		(fp_rect
			(start -0.508 0.9398)
			(end 0.508 -0.9398)
			(stroke
				(width 0)
				(type default)
			)
			(fill no)
			(layer "F.Fab")
		)
		(pad "1" smd custom
			(at 0 -0.4445)
			(size 0.1397 0.1397)
			(layers "F.Cu" "F.Mask" "F.Paste")
			(net "BMC_I2C9_CLKBUF2_SDA_R")
			(options
				(clearance outline)
				(anchor circle)
			)
			(primitives
				(gr_poly
					(pts
						(arc
							(start -0.1778 -0.2794)
							(mid -0.249642 -0.249642)
							(end -0.2794 -0.1778)
						)
						(arc
							(start -0.2794 0.1778)
							(mid -0.249642 0.249642)
							(end -0.1778 0.2794)
						)
						(arc
							(start 0.1778 0.2794)
							(mid 0.249642 0.249642)
							(end 0.2794 0.1778)
						)
						(arc
							(start 0.2794 -0.1778)
							(mid 0.249642 -0.249642)
							(end 0.1778 -0.2794)
						)
					)
					(width 0)
					(fill yes)
				)
			)
		)
		(pad "2" smd custom
			(at 0 0.4445)
			(size 0.1397 0.1397)
			(layers "F.Cu" "F.Mask" "F.Paste")
			(net "BMC_I2C9_CLKBUF2_SDA")
			(options
				(clearance outline)
				(anchor circle)
			)
			(primitives
				(gr_poly
					(pts
						(arc
							(start -0.1778 -0.2794)
							(mid -0.249642 -0.249642)
							(end -0.2794 -0.1778)
						)
						(arc
							(start -0.2794 0.1778)
							(mid -0.249642 0.249642)
							(end -0.1778 0.2794)
						)
						(arc
							(start 0.1778 0.2794)
							(mid 0.249642 0.249642)
							(end 0.2794 0.1778)
						)
						(arc
							(start 0.2794 -0.1778)
							(mid 0.249642 -0.249642)
							(end 0.1778 -0.2794)
						)
					)
					(width 0)
					(fill yes)
				)
			)
		)
	)
	(footprint ""
		(layer "F.Cu")
		(at 310.007 -67.7926)
		(property "Reference" "PG65"
			(at 0 0 0)
			(layer "F.SilkS")
			(hide yes)
			(effects
				(font
					(size 1.27 1.27)
				)
			)
		)
		(property "Value" "GAP-CLOSE-PWR-3-GP"
			(at 0.0254 -6.5786 0)
			(unlocked yes)
			(layer "F.Fab")
			(hide yes)
			(effects
				(font
					(size 1.016 1.016)
					(thickness 0.1524)
				)
			)
		)
		(property "Device Type" "GAP-CLOSE-PWR-3"
			(at 0.0254 -8.255 0)
			(unlocked yes)
			(layer "F.Fab")
			(hide yes)
			(effects
				(font
					(size 1.016 1.016)
					(thickness 0.1524)
				)
			)
		)
		(duplicate_pad_numbers_are_jumpers no)
		(fp_rect
			(start -0.7112 0.4572)
			(end 0.7112 -0.4572)
			(stroke
				(width 0)
				(type default)
			)
			(fill no)
			(layer "F.CrtYd")
		)
		(fp_poly
			(pts
				(xy -0.7112 -0.4572) (xy 0.7112 -0.4572) (xy 0.7112 0.4572) (xy -0.7112 0.4572)
			)
			(stroke
				(width 0)
				(type default)
			)
			(fill no)
			(layer "F.Fab")
		)
		(pad "1" smd rect
			(at -0.3048 0)
			(size 0.6604 0.762)
			(layers "F.Cu" "F.Mask" "F.Paste")
			(net "DUT_VDD")
		)
		(pad "2" smd rect
			(at 0.3048 0)
			(size 0.6604 0.762)
			(layers "F.Cu" "F.Mask" "F.Paste")
			(net "P0V9_E")
		)
	)
	(footprint ""
		(layer "F.Cu")
		(at 187.071 -6.604)
		(property "Reference" "R529"
			(at 0 0 0)
			(layer "F.SilkS")
			(hide yes)
			(effects
				(font
					(size 1.27 1.27)
				)
			)
		)
		(property "Value" "1KR2F-3-GP"
			(at 0.064008 -3.993896 0)
			(unlocked yes)
			(layer "F.Fab")
			(hide yes)
			(effects
				(font
					(size 1.016 1.016)
					(thickness 0.1524)
				)
			)
		)
		(property "Device Type" "R402H16"
			(at 0.064008 -5.517896 0)
			(unlocked yes)
			(layer "F.Fab")
			(hide yes)
			(effects
				(font
					(size 1.016 1.016)
					(thickness 0.1524)
				)
			)
		)
		(duplicate_pad_numbers_are_jumpers no)
		(fp_line
			(start -0.508 -0.9398)
			(end -0.508 0.9398)
			(stroke
				(width 0.1524)
				(type default)
			)
			(layer "F.SilkS")
		)
		(fp_line
			(start 0.508 -0.9398)
			(end -0.508 -0.9398)
			(stroke
				(width 0.1524)
				(type default)
			)
			(layer "F.SilkS")
		)
		(fp_rect
			(start -0.508 0.9398)
			(end 0.508 -0.9398)
			(stroke
				(width 0)
				(type default)
			)
			(fill no)
			(layer "F.CrtYd")
		)
		(fp_rect
			(start -0.508 0.9398)
			(end 0.508 -0.9398)
			(stroke
				(width 0)
				(type default)
			)
			(fill no)
			(layer "F.Fab")
		)
		(pad "1" smd custom
			(at 0 -0.4445)
			(size 0.1397 0.1397)
			(layers "F.Cu" "F.Mask" "F.Paste")
			(net "ENCLO_LED_RED_G")
			(options
				(clearance outline)
				(anchor circle)
			)
			(primitives
				(gr_poly
					(pts
						(arc
							(start -0.1778 -0.2794)
							(mid -0.249642 -0.249642)
							(end -0.2794 -0.1778)
						)
						(arc
							(start -0.2794 0.1778)
							(mid -0.249642 0.249642)
							(end -0.1778 0.2794)
						)
						(arc
							(start 0.1778 0.2794)
							(mid 0.249642 0.249642)
							(end 0.2794 0.1778)
						)
						(arc
							(start 0.2794 -0.1778)
							(mid 0.249642 -0.249642)
							(end 0.1778 -0.2794)
						)
					)
					(width 0)
					(fill yes)
				)
			)
		)
		(pad "2" smd custom
			(at 0 0.4445)
			(size 0.1397 0.1397)
			(layers "F.Cu" "F.Mask" "F.Paste")
			(net "GND")
			(options
				(clearance outline)
				(anchor circle)
			)
			(primitives
				(gr_poly
					(pts
						(arc
							(start -0.1778 -0.2794)
							(mid -0.249642 -0.249642)
							(end -0.2794 -0.1778)
						)
						(arc
							(start -0.2794 0.1778)
							(mid -0.249642 0.249642)
							(end -0.1778 0.2794)
						)
						(arc
							(start 0.1778 0.2794)
							(mid 0.249642 0.249642)
							(end 0.2794 0.1778)
						)
						(arc
							(start 0.2794 -0.1778)
							(mid 0.249642 -0.249642)
							(end 0.1778 -0.2794)
						)
					)
					(width 0)
					(fill yes)
				)
			)
		)
	)
	(footprint ""
		(layer "F.Cu")
		(at 18.796 -145.796 180)
		(property "Reference" "C194"
			(at 0 0 180)
			(layer "F.SilkS")
			(hide yes)
			(effects
				(font
					(size 1.27 1.27)
				)
			)
		)
		(property "Value" "SC1U10V2KX-4-GP"
			(at 1.1811 -2.7051 180)
			(unlocked yes)
			(layer "F.Fab")
			(hide yes)
			(effects
				(font
					(size 1.016 1.016)
					(thickness 0.1524)
				)
			)
		)
		(property "Device Type" "C402H22"
			(at 1.1811 -4.2291 180)
			(unlocked yes)
			(layer "F.Fab")
			(hide yes)
			(effects
				(font
					(size 1.016 1.016)
					(thickness 0.1524)
				)
			)
		)
		(duplicate_pad_numbers_are_jumpers no)
		(fp_rect
			(start -0.4318 0.9525)
			(end 0.4318 -0.9525)
			(stroke
				(width 0)
				(type default)
			)
			(fill no)
			(layer "F.CrtYd")
		)
		(fp_rect
			(start -0.4318 0.9525)
			(end 0.4318 -0.9525)
			(stroke
				(width 0)
				(type default)
			)
			(fill no)
			(layer "F.Fab")
		)
		(pad "1" smd custom
			(at 0 -0.4445 180)
			(size 0.1524 0.1524)
			(layers "F.Cu" "F.Mask" "F.Paste")
			(net "MPLLAV33")
			(options
				(clearance outline)
				(anchor circle)
			)
			(primitives
				(gr_poly
					(pts
						(arc
							(start 0.3048 -0.2032)
							(mid 0.275042 -0.275042)
							(end 0.2032 -0.3048)
						)
						(arc
							(start -0.2032 -0.3048)
							(mid -0.275042 -0.275042)
							(end -0.3048 -0.2032)
						)
						(arc
							(start -0.3048 0.2032)
							(mid -0.275042 0.275042)
							(end -0.2032 0.3048)
						)
						(arc
							(start 0.2032 0.3048)
							(mid 0.275042 0.275042)
							(end 0.3048 0.2032)
						)
					)
					(width 0)
					(fill yes)
				)
			)
		)
		(pad "2" smd custom
			(at 0 0.4445 180)
			(size 0.1524 0.1524)
			(layers "F.Cu" "F.Mask" "F.Paste")
			(net "GND")
			(options
				(clearance outline)
				(anchor circle)
			)
			(primitives
				(gr_poly
					(pts
						(arc
							(start 0.3048 -0.2032)
							(mid 0.275042 -0.275042)
							(end 0.2032 -0.3048)
						)
						(arc
							(start -0.2032 -0.3048)
							(mid -0.275042 -0.275042)
							(end -0.3048 -0.2032)
						)
						(arc
							(start -0.3048 0.2032)
							(mid -0.275042 0.275042)
							(end -0.2032 0.3048)
						)
						(arc
							(start 0.2032 0.3048)
							(mid 0.275042 0.275042)
							(end 0.3048 0.2032)
						)
					)
					(width 0)
					(fill yes)
				)
			)
		)
	)
	(footprint ""
		(layer "F.Cu")
		(at 87.007954 -212.420454 180)
		(property "Reference" "C348"
			(at 0 0 180)
			(layer "F.SilkS")
			(hide yes)
			(effects
				(font
					(size 1.27 1.27)
				)
			)
		)
		(property "Value" "SCD22U10V2KX-1GP"
			(at 1.1811 -2.7051 180)
			(unlocked yes)
			(layer "F.Fab")
			(hide yes)
			(effects
				(font
					(size 1.016 1.016)
					(thickness 0.1524)
				)
			)
		)
		(property "Device Type" "C402H22"
			(at 1.1811 -4.2291 180)
			(unlocked yes)
			(layer "F.Fab")
			(hide yes)
			(effects
				(font
					(size 1.016 1.016)
					(thickness 0.1524)
				)
			)
		)
		(duplicate_pad_numbers_are_jumpers no)
		(fp_rect
			(start -0.4318 0.9525)
			(end 0.4318 -0.9525)
			(stroke
				(width 0)
				(type default)
			)
			(fill no)
			(layer "F.CrtYd")
		)
		(fp_rect
			(start -0.4318 0.9525)
			(end 0.4318 -0.9525)
			(stroke
				(width 0)
				(type default)
			)
			(fill no)
			(layer "F.Fab")
		)
		(pad "1" smd custom
			(at 0 -0.4445 180)
			(size 0.1524 0.1524)
			(layers "F.Cu" "F.Mask" "F.Paste")
			(net "PCIE_TX_CAP_N66")
			(options
				(clearance outline)
				(anchor circle)
			)
			(primitives
				(gr_poly
					(pts
						(arc
							(start 0.3048 -0.2032)
							(mid 0.275042 -0.275042)
							(end 0.2032 -0.3048)
						)
						(arc
							(start -0.2032 -0.3048)
							(mid -0.275042 -0.275042)
							(end -0.3048 -0.2032)
						)
						(arc
							(start -0.3048 0.2032)
							(mid -0.275042 0.275042)
							(end -0.2032 0.3048)
						)
						(arc
							(start 0.2032 0.3048)
							(mid 0.275042 0.275042)
							(end 0.3048 0.2032)
						)
					)
					(width 0)
					(fill yes)
				)
			)
		)
		(pad "2" smd custom
			(at 0 0.4445 180)
			(size 0.1524 0.1524)
			(layers "F.Cu" "F.Mask" "F.Paste")
			(net "PCIE_TX_N66")
			(options
				(clearance outline)
				(anchor circle)
			)
			(primitives
				(gr_poly
					(pts
						(arc
							(start 0.3048 -0.2032)
							(mid 0.275042 -0.275042)
							(end 0.2032 -0.3048)
						)
						(arc
							(start -0.2032 -0.3048)
							(mid -0.275042 -0.275042)
							(end -0.3048 -0.2032)
						)
						(arc
							(start -0.3048 0.2032)
							(mid -0.275042 0.275042)
							(end -0.2032 0.3048)
						)
						(arc
							(start 0.2032 0.3048)
							(mid 0.275042 0.275042)
							(end 0.3048 0.2032)
						)
					)
					(width 0)
					(fill yes)
				)
			)
		)
	)
	(footprint ""
		(layer "F.Cu")
		(at 41.3766 -60.77966 180)
		(property "Reference" "R46"
			(at 0 0 180)
			(layer "F.SilkS")
			(hide yes)
			(effects
				(font
					(size 1.27 1.27)
				)
			)
		)
		(property "Value" "100KR2F-L1-GP"
			(at 0.064008 -3.993896 180)
			(unlocked yes)
			(layer "F.Fab")
			(hide yes)
			(effects
				(font
					(size 1.016 1.016)
					(thickness 0.1524)
				)
			)
		)
		(property "Device Type" "R402H16"
			(at 0.064008 -5.517896 180)
			(unlocked yes)
			(layer "F.Fab")
			(hide yes)
			(effects
				(font
					(size 1.016 1.016)
					(thickness 0.1524)
				)
			)
		)
		(duplicate_pad_numbers_are_jumpers no)
		(fp_line
			(start 0.508 -0.9398)
			(end -0.508 -0.9398)
			(stroke
				(width 0.1524)
				(type default)
			)
			(layer "F.SilkS")
		)
		(fp_line
			(start -0.508 -0.9398)
			(end -0.508 0.9398)
			(stroke
				(width 0.1524)
				(type default)
			)
			(layer "F.SilkS")
		)
		(fp_rect
			(start -0.508 0.9398)
			(end 0.508 -0.9398)
			(stroke
				(width 0)
				(type default)
			)
			(fill no)
			(layer "F.CrtYd")
		)
		(fp_rect
			(start -0.508 0.9398)
			(end 0.508 -0.9398)
			(stroke
				(width 0)
				(type default)
			)
			(fill no)
			(layer "F.Fab")
		)
		(pad "1" smd custom
			(at 0 -0.4445 180)
			(size 0.1397 0.1397)
			(layers "F.Cu" "F.Mask" "F.Paste")
			(net "USB5V_EN")
			(options
				(clearance outline)
				(anchor circle)
			)
			(primitives
				(gr_poly
					(pts
						(arc
							(start -0.1778 -0.2794)
							(mid -0.249642 -0.249642)
							(end -0.2794 -0.1778)
						)
						(arc
							(start -0.2794 0.1778)
							(mid -0.249642 0.249642)
							(end -0.1778 0.2794)
						)
						(arc
							(start 0.1778 0.2794)
							(mid 0.249642 0.249642)
							(end 0.2794 0.1778)
						)
						(arc
							(start 0.2794 -0.1778)
							(mid 0.249642 -0.249642)
							(end 0.1778 -0.2794)
						)
					)
					(width 0)
					(fill yes)
				)
			)
		)
		(pad "2" smd custom
			(at 0 0.4445 180)
			(size 0.1397 0.1397)
			(layers "F.Cu" "F.Mask" "F.Paste")
			(net "P5V_STBY")
			(options
				(clearance outline)
				(anchor circle)
			)
			(primitives
				(gr_poly
					(pts
						(arc
							(start -0.1778 -0.2794)
							(mid -0.249642 -0.249642)
							(end -0.2794 -0.1778)
						)
						(arc
							(start -0.2794 0.1778)
							(mid -0.249642 0.249642)
							(end -0.1778 0.2794)
						)
						(arc
							(start 0.1778 0.2794)
							(mid 0.249642 0.249642)
							(end 0.2794 0.1778)
						)
						(arc
							(start 0.2794 -0.1778)
							(mid 0.249642 -0.249642)
							(end 0.1778 -0.2794)
						)
					)
					(width 0)
					(fill yes)
				)
			)
		)
	)
	(footprint ""
		(layer "F.Cu")
		(at 246.7356 -9.0424)
		(property "Reference" "C477"
			(at 0 0 0)
			(layer "F.SilkS")
			(hide yes)
			(effects
				(font
					(size 1.27 1.27)
				)
			)
		)
		(property "Value" "SC4D7U16V5KX-1-GP"
			(at -0.0762 -6.1214 0)
			(unlocked yes)
			(layer "F.Fab")
			(hide yes)
			(effects
				(font
					(size 1.016 1.016)
					(thickness 0.1524)
				)
			)
		)
		(property "Device Type" "C805H56"
			(at -0.0762 -8.1534 0)
			(unlocked yes)
			(layer "F.Fab")
			(hide yes)
			(effects
				(font
					(size 1.016 1.016)
					(thickness 0.1524)
				)
			)
		)
		(duplicate_pad_numbers_are_jumpers no)
		(fp_line
			(start 0.635 0)
			(end -0.635 0)
			(stroke
				(width 0.508)
				(type default)
			)
			(layer "F.SilkS")
		)
		(fp_rect
			(start -0.9652 1.778)
			(end 0.9652 -1.778)
			(stroke
				(width 0)
				(type default)
			)
			(fill no)
			(layer "F.CrtYd")
		)
		(fp_poly
			(pts
				(xy -0.9652 -1.778) (xy 0.9652 -1.778) (xy 0.9652 1.778) (xy -0.9652 1.778)
			)
			(stroke
				(width 0)
				(type default)
			)
			(fill no)
			(layer "F.Fab")
		)
		(pad "1" smd rect
			(at 0 -0.9652)
			(size 1.397 1.143)
			(layers "F.Cu" "F.Mask" "F.Paste")
			(net "DUT_VDDO")
		)
		(pad "2" smd rect
			(at 0 0.9652)
			(size 1.397 1.143)
			(layers "F.Cu" "F.Mask" "F.Paste")
			(net "GND")
		)
	)
	(footprint ""
		(layer "F.Cu")
		(at 53.721 -122.428 -90)
		(property "Reference" "R801"
			(at 0 0 270)
			(layer "F.SilkS")
			(hide yes)
			(effects
				(font
					(size 1.27 1.27)
				)
			)
		)
		(property "Value" "4K7R2F-GP"
			(at 0.064008 -3.993896 270)
			(unlocked yes)
			(layer "F.Fab")
			(hide yes)
			(effects
				(font
					(size 1.016 1.016)
					(thickness 0.1524)
				)
			)
		)
		(property "Device Type" "R402H16"
			(at 0.064008 -5.517896 270)
			(unlocked yes)
			(layer "F.Fab")
			(hide yes)
			(effects
				(font
					(size 1.016 1.016)
					(thickness 0.1524)
				)
			)
		)
		(duplicate_pad_numbers_are_jumpers no)
		(fp_line
			(start -0.508 -0.9398)
			(end -0.508 0.9398)
			(stroke
				(width 0.1524)
				(type default)
			)
			(layer "F.SilkS")
		)
		(fp_line
			(start 0.508 -0.9398)
			(end -0.508 -0.9398)
			(stroke
				(width 0.1524)
				(type default)
			)
			(layer "F.SilkS")
		)
		(fp_rect
			(start -0.508 0.9398)
			(end 0.508 -0.9398)
			(stroke
				(width 0)
				(type default)
			)
			(fill no)
			(layer "F.CrtYd")
		)
		(fp_rect
			(start -0.508 0.9398)
			(end 0.508 -0.9398)
			(stroke
				(width 0)
				(type default)
			)
			(fill no)
			(layer "F.Fab")
		)
		(pad "1" smd custom
			(at 0 -0.4445 270)
			(size 0.1397 0.1397)
			(layers "F.Cu" "F.Mask" "F.Paste")
			(net "P3V3_STBY")
			(options
				(clearance outline)
				(anchor circle)
			)
			(primitives
				(gr_poly
					(pts
						(arc
							(start -0.1778 -0.2794)
							(mid -0.249642 -0.249642)
							(end -0.2794 -0.1778)
						)
						(arc
							(start -0.2794 0.1778)
							(mid -0.249642 0.249642)
							(end -0.1778 0.2794)
						)
						(arc
							(start 0.1778 0.2794)
							(mid 0.249642 0.249642)
							(end 0.2794 0.1778)
						)
						(arc
							(start 0.2794 -0.1778)
							(mid 0.249642 -0.249642)
							(end 0.1778 -0.2794)
						)
					)
					(width 0)
					(fill yes)
				)
			)
		)
		(pad "2" smd custom
			(at 0 0.4445 270)
			(size 0.1397 0.1397)
			(layers "F.Cu" "F.Mask" "F.Paste")
			(net "JTAG_BMC_TRST_N")
			(options
				(clearance outline)
				(anchor circle)
			)
			(primitives
				(gr_poly
					(pts
						(arc
							(start -0.1778 -0.2794)
							(mid -0.249642 -0.249642)
							(end -0.2794 -0.1778)
						)
						(arc
							(start -0.2794 0.1778)
							(mid -0.249642 0.249642)
							(end -0.1778 0.2794)
						)
						(arc
							(start 0.1778 0.2794)
							(mid 0.249642 0.249642)
							(end 0.2794 0.1778)
						)
						(arc
							(start 0.2794 -0.1778)
							(mid 0.249642 -0.249642)
							(end 0.1778 -0.2794)
						)
					)
					(width 0)
					(fill yes)
				)
			)
		)
	)
)
